(kicad_pcb
	(version 20260206)
	(generator "pcbnew")
	(generator_version "10.0")
	(general
		(thickness 1.6)
		(legacy_teardrops no)
	)
	(paper "A4")
	(title_block
		(title "01162023_DA0F0TEBIF0_F0T_Expander_BD_F_brd_V02_OCP.brd")
		(comment 1 "Grand Teton / footprints 8710-8716 of 9728")
	)
	(layers
		(0 "F.Cu" signal "TOP")
		(4 "In1.Cu" signal "GND")
		(6 "In2.Cu" signal "VCC")
		(8 "In3.Cu" signal "VCC1")
		(10 "In4.Cu" signal "GND1")
		(12 "In5.Cu" signal "IN1")
		(14 "In6.Cu" signal "GND2")
		(16 "In7.Cu" signal "IN2")
		(18 "In8.Cu" signal "GND3")
		(20 "In9.Cu" signal "IN3")
		(22 "In10.Cu" signal "GND4")
		(24 "In11.Cu" signal "IN4")
		(26 "In12.Cu" signal "GND5")
		(28 "In13.Cu" signal "IN5")
		(30 "In14.Cu" signal "GND6")
		(32 "In15.Cu" signal "IN6")
		(34 "In16.Cu" signal "GND7")
		(2 "B.Cu" signal "BOTTOM")
		(9 "F.Adhes" user "F.Adhesive")
		(11 "B.Adhes" user "B.Adhesive")
		(13 "F.Paste" user "Package Geometry/Pastemask Top")
		(15 "B.Paste" user "Package Geometry/Pastemask Bottom")
		(5 "F.SilkS" user "Ref Des/Silkscreen Top")
		(7 "B.SilkS" user "Ref Des/Silkscreen Bottom")
		(1 "F.Mask" user "Board Geometry/Soldermask Top")
		(3 "B.Mask" user "Board Geometry/Soldermask Bottom")
		(17 "Dwgs.User" user "User.Drawings")
		(19 "Cmts.User" user "User.Comments")
		(21 "Eco1.User" user "User.Eco1")
		(23 "Eco2.User" user "User.Eco2")
		(25 "Edge.Cuts" user "Board Geometry/Outline")
		(27 "Margin" user)
		(31 "F.CrtYd" user "Package Geometry/Place Bound Top")
		(29 "B.CrtYd" user "Package Geometry/Place Bound Bottom")
		(35 "F.Fab" user "Ref Des/Assembly Top")
		(33 "B.Fab" user "Ref Des/Assembly Bottom")
	)
	(footprint ""
		(layer "B.Cu")
		(at 133.230366 -181.249574 180)
		(property "Reference" "C2654"
			(at 0 0 0)
			(layer "B.SilkS")
			(hide yes)
			(effects
				(font
					(size 1.27 1.27)
				)
				(justify mirror)
			)
		)
		(property "Value" ""
			(at 0 0 0)
			(layer "B.Fab")
			(effects
				(font
					(size 1.27 1.27)
				)
				(justify mirror)
			)
		)
		(duplicate_pad_numbers_are_jumpers no)
		(fp_line
			(start 0.7874 0.4064)
			(end 0.7874 -0.4064)
			(stroke
				(width 0.1524)
				(type default)
			)
			(layer "B.SilkS")
		)
		(fp_line
			(start 0.7874 -0.4064)
			(end -0.7874 -0.4064)
			(stroke
				(width 0.1524)
				(type default)
			)
			(layer "B.SilkS")
		)
		(fp_line
			(start -0.7874 0.4064)
			(end 0.7874 0.4064)
			(stroke
				(width 0.1524)
				(type default)
			)
			(layer "B.SilkS")
		)
		(fp_line
			(start -0.7874 -0.4064)
			(end -0.7874 0.4064)
			(stroke
				(width 0.1524)
				(type default)
			)
			(layer "B.SilkS")
		)
		(fp_line
			(start 0.67945 0.3048)
			(end 0.67945 -0.305054)
			(stroke
				(width 0.1)
				(type default)
			)
			(layer "B.Fab")
		)
		(fp_line
			(start 0.67945 -0.305054)
			(end 0.12065 -0.305054)
			(stroke
				(width 0.1)
				(type default)
			)
			(layer "B.Fab")
		)
		(fp_line
			(start 0.12065 0.3048)
			(end 0.67945 0.3048)
			(stroke
				(width 0.1)
				(type default)
			)
			(layer "B.Fab")
		)
		(fp_line
			(start 0.12065 0.2794)
			(end 0.12065 0.3048)
			(stroke
				(width 0.1)
				(type default)
			)
			(layer "B.Fab")
		)
		(fp_line
			(start 0.12065 -0.2794)
			(end -0.12065 -0.2794)
			(stroke
				(width 0.1)
				(type default)
			)
			(layer "B.Fab")
		)
		(fp_line
			(start 0.12065 -0.305054)
			(end 0.12065 -0.2794)
			(stroke
				(width 0.1)
				(type default)
			)
			(layer "B.Fab")
		)
		(fp_line
			(start -0.120396 0.3048)
			(end -0.120396 0.2794)
			(stroke
				(width 0.1)
				(type default)
			)
			(layer "B.Fab")
		)
		(fp_line
			(start -0.120396 0.2794)
			(end 0.12065 0.2794)
			(stroke
				(width 0.1)
				(type default)
			)
			(layer "B.Fab")
		)
		(fp_line
			(start -0.12065 -0.2794)
			(end -0.12065 -0.3048)
			(stroke
				(width 0.1)
				(type default)
			)
			(layer "B.Fab")
		)
		(fp_line
			(start -0.12065 -0.3048)
			(end -0.67945 -0.3048)
			(stroke
				(width 0.1)
				(type default)
			)
			(layer "B.Fab")
		)
		(fp_line
			(start -0.67945 0.3048)
			(end -0.120396 0.3048)
			(stroke
				(width 0.1)
				(type default)
			)
			(layer "B.Fab")
		)
		(fp_line
			(start -0.67945 -0.3048)
			(end -0.67945 0.3048)
			(stroke
				(width 0.1)
				(type default)
			)
			(layer "B.Fab")
		)
		(pad "1" smd circle
			(at 0.40005 0)
			(size 0 0)
			(layers "B.Cu" "B.Mask" "B.Paste")
			(net "P3V3_DB2000QL_VDDA")
		)
		(pad "2" smd circle
			(at -0.40005 0)
			(size 0 0)
			(layers "B.Cu" "B.Mask" "B.Paste")
			(net "GND")
		)
	)
	(footprint ""
		(layer "B.Cu")
		(at 52.999894 -288.299906 90)
		(property "Reference" "C2935"
			(at 0 0 90)
			(layer "B.SilkS")
			(hide yes)
			(effects
				(font
					(size 1.27 1.27)
				)
				(justify mirror)
			)
		)
		(property "Value" ""
			(at 0 0 90)
			(layer "B.Fab")
			(effects
				(font
					(size 1.27 1.27)
				)
				(justify mirror)
			)
		)
		(duplicate_pad_numbers_are_jumpers no)
		(fp_line
			(start 0.299974 -0.150114)
			(end -0.299974 -0.150114)
			(stroke
				(width 0.1)
				(type default)
			)
			(layer "B.Fab")
		)
		(fp_line
			(start -0.299974 -0.150114)
			(end -0.299974 0.150114)
			(stroke
				(width 0.1)
				(type default)
			)
			(layer "B.Fab")
		)
		(fp_line
			(start 0.299974 0.150114)
			(end 0.299974 -0.150114)
			(stroke
				(width 0.1)
				(type default)
			)
			(layer "B.Fab")
		)
		(fp_line
			(start -0.299974 0.150114)
			(end 0.299974 0.150114)
			(stroke
				(width 0.1)
				(type default)
			)
			(layer "B.Fab")
		)
		(pad "1" smd rect
			(at 0.2667 0 270)
			(size 0.3048 0.381)
			(layers "B.Cu" "B.Mask" "B.Paste")
			(net "P1V25_PEX0")
		)
		(pad "2" smd rect
			(at -0.2667 0 270)
			(size 0.3048 0.381)
			(layers "B.Cu" "B.Mask" "B.Paste")
			(net "GND")
		)
	)
	(footprint ""
		(layer "B.Cu")
		(at 412.224982 -286.399732 90)
		(property "Reference" "C3505"
			(at 0 0 90)
			(layer "B.SilkS")
			(hide yes)
			(effects
				(font
					(size 1.27 1.27)
				)
				(justify mirror)
			)
		)
		(property "Value" ""
			(at 0 0 90)
			(layer "B.Fab")
			(effects
				(font
					(size 1.27 1.27)
				)
				(justify mirror)
			)
		)
		(duplicate_pad_numbers_are_jumpers no)
		(fp_line
			(start 0.299974 -0.150114)
			(end -0.299974 -0.150114)
			(stroke
				(width 0.1)
				(type default)
			)
			(layer "B.Fab")
		)
		(fp_line
			(start -0.299974 -0.150114)
			(end -0.299974 0.150114)
			(stroke
				(width 0.1)
				(type default)
			)
			(layer "B.Fab")
		)
		(fp_line
			(start 0.299974 0.150114)
			(end 0.299974 -0.150114)
			(stroke
				(width 0.1)
				(type default)
			)
			(layer "B.Fab")
		)
		(fp_line
			(start -0.299974 0.150114)
			(end 0.299974 0.150114)
			(stroke
				(width 0.1)
				(type default)
			)
			(layer "B.Fab")
		)
		(pad "1" smd rect
			(at 0.2667 0 270)
			(size 0.3048 0.381)
			(layers "B.Cu" "B.Mask" "B.Paste")
			(net "P1V25_SERDES_VDDPLL_PEX3")
		)
		(pad "2" smd rect
			(at -0.2667 0 270)
			(size 0.3048 0.381)
			(layers "B.Cu" "B.Mask" "B.Paste")
			(net "GND")
		)
	)
	(footprint ""
		(layer "B.Cu")
		(at 19.755612 -227.084382 90)
		(property "Reference" "U65"
			(at -2.069592 3.18135 270)
			(unlocked yes)
			(layer "B.SilkS")
			(effects
				(font
					(size 0.7874 0.5842)
					(thickness 0.1524)
				)
				(justify mirror)
			)
		)
		(property "Value" ""
			(at 0 0 90)
			(layer "B.Fab")
			(effects
				(font
					(size 1.27 1.27)
				)
				(justify mirror)
			)
		)
		(duplicate_pad_numbers_are_jumpers no)
		(fp_line
			(start 1.8288 -2.4892)
			(end 0.5588 -2.4892)
			(stroke
				(width 0.1524)
				(type default)
			)
			(layer "B.SilkS")
		)
		(fp_line
			(start 0.5588 -2.4892)
			(end 0 -1.9304)
			(stroke
				(width 0.1524)
				(type default)
			)
			(layer "B.SilkS")
		)
		(fp_line
			(start -0.5588 -2.4892)
			(end -1.8288 -2.4892)
			(stroke
				(width 0.1524)
				(type default)
			)
			(layer "B.SilkS")
		)
		(fp_line
			(start -1.8288 -2.4892)
			(end -1.8161 2.4892)
			(stroke
				(width 0.1524)
				(type default)
			)
			(layer "B.SilkS")
		)
		(fp_line
			(start 0 -1.9304)
			(end -0.5588 -2.4892)
			(stroke
				(width 0.1524)
				(type default)
			)
			(layer "B.SilkS")
		)
		(fp_line
			(start 1.8288 2.4892)
			(end 1.8288 -2.4892)
			(stroke
				(width 0.1524)
				(type default)
			)
			(layer "B.SilkS")
		)
		(fp_line
			(start -1.8161 2.4892)
			(end 1.8288 2.4892)
			(stroke
				(width 0.1524)
				(type default)
			)
			(layer "B.SilkS")
		)
		(fp_poly
			(pts
				(xy 4.12242 -2.832862) (xy 3.680714 -3.274822) (xy 3.521202 -2.650998)
			)
			(stroke
				(width 0)
				(type default)
			)
			(fill yes)
			(layer "B.SilkS")
		)
		(fp_line
			(start 1.9939 -2.4892)
			(end -1.9939 -2.4892)
			(stroke
				(width 0.1)
				(type default)
			)
			(layer "B.Fab")
		)
		(fp_line
			(start -1.9939 -2.4892)
			(end -1.9939 -2.3876)
			(stroke
				(width 0.1)
				(type default)
			)
			(layer "B.Fab")
		)
		(fp_line
			(start 3.0988 -2.3876)
			(end 1.9939 -2.3876)
			(stroke
				(width 0.1)
				(type default)
			)
			(layer "B.Fab")
		)
		(fp_line
			(start 1.9939 -2.3876)
			(end 1.9939 -2.4892)
			(stroke
				(width 0.1)
				(type default)
			)
			(layer "B.Fab")
		)
		(fp_line
			(start 1.9939 -2.3876)
			(end 1.9812 -2.3876)
			(stroke
				(width 0.1)
				(type default)
			)
			(layer "B.Fab")
		)
		(fp_line
			(start -1.9939 -2.3876)
			(end -3.0988 -2.3876)
			(stroke
				(width 0.1)
				(type default)
			)
			(layer "B.Fab")
		)
		(fp_line
			(start -1.9939 -2.3876)
			(end -1.9939 2.3876)
			(stroke
				(width 0.1)
				(type default)
			)
			(layer "B.Fab")
		)
		(fp_line
			(start -3.0988 -2.3876)
			(end -3.0988 2.3876)
			(stroke
				(width 0.1)
				(type default)
			)
			(layer "B.Fab")
		)
		(fp_line
			(start -3.0988 -2.3876)
			(end -3.0988 2.3876)
			(stroke
				(width 0.1)
				(type default)
			)
			(layer "B.Fab")
		)
		(fp_line
			(start 3.0988 2.3876)
			(end 3.0988 -2.3876)
			(stroke
				(width 0.1)
				(type default)
			)
			(layer "B.Fab")
		)
		(fp_line
			(start 3.0988 2.3876)
			(end 3.0988 -2.3876)
			(stroke
				(width 0.1)
				(type default)
			)
			(layer "B.Fab")
		)
		(fp_line
			(start 1.9939 2.3876)
			(end 1.9939 -2.3876)
			(stroke
				(width 0.1)
				(type default)
			)
			(layer "B.Fab")
		)
		(fp_line
			(start 1.9939 2.3876)
			(end 3.0988 2.3876)
			(stroke
				(width 0.1)
				(type default)
			)
			(layer "B.Fab")
		)
		(fp_line
			(start -1.9939 2.3876)
			(end -1.9939 2.4892)
			(stroke
				(width 0.1)
				(type default)
			)
			(layer "B.Fab")
		)
		(fp_line
			(start -3.0988 2.3876)
			(end -1.9939 2.3876)
			(stroke
				(width 0.1)
				(type default)
			)
			(layer "B.Fab")
		)
		(fp_line
			(start 1.9939 2.4892)
			(end 1.9939 2.3876)
			(stroke
				(width 0.1)
				(type default)
			)
			(layer "B.Fab")
		)
		(fp_line
			(start -1.9939 2.4892)
			(end 1.9939 2.4892)
			(stroke
				(width 0.1)
				(type default)
			)
			(layer "B.Fab")
		)
		(fp_line
			(start -1.9939 2.4892)
			(end -2.0066 2.4892)
			(stroke
				(width 0.1)
				(type default)
			)
			(layer "B.Fab")
		)
		(fp_line
			(start -1.9939 2.5019)
			(end -1.9939 2.4892)
			(stroke
				(width 0.1)
				(type default)
			)
			(layer "B.Fab")
		)
		(fp_poly
			(pts
				(xy 4.23672 -1.989328) (xy 4.23672 -2.614168) (xy 3.683 -2.286)
			)
			(stroke
				(width 0)
				(type default)
			)
			(fill yes)
			(layer "B.Fab")
		)
		(pad "1" smd rect
			(at 2.7432 -2.2225)
			(size 0.3556 1.5494)
			(layers "B.Cu" "B.Mask" "B.Paste")
			(net "SEL_FLASH_PEX0_BUF_R")
		)
		(pad "2" smd rect
			(at 2.7432 -1.5875)
			(size 0.3556 1.5494)
			(layers "B.Cu" "B.Mask" "B.Paste")
			(net "SPI_PEX0_CS_R_N")
		)
		(pad "3" smd rect
			(at 2.7432 -0.9525)
			(size 0.3556 1.5494)
			(layers "B.Cu" "B.Mask" "B.Paste")
			(net "SPI_BIC1_CS0_LS01_R1_N")
		)
		(pad "4" smd rect
			(at 2.7432 -0.3175)
			(size 0.3556 1.5494)
			(layers "B.Cu" "B.Mask" "B.Paste")
			(net "SPI_PEX0_CS_MUX_N")
		)
		(pad "5" smd rect
			(at 2.7432 0.3175)
			(size 0.3556 1.5494)
			(layers "B.Cu" "B.Mask" "B.Paste")
			(net "SPI_PEX0_CLK_R")
		)
		(pad "6" smd rect
			(at 2.7432 0.9525)
			(size 0.3556 1.5494)
			(layers "B.Cu" "B.Mask" "B.Paste")
			(net "SPI_BIC1_CLK_LS01_R1")
		)
		(pad "7" smd rect
			(at 2.7432 1.5875)
			(size 0.3556 1.5494)
			(layers "B.Cu" "B.Mask" "B.Paste")
			(net "SPI_PEX0_CLK_MUX")
		)
		(pad "8" smd rect
			(at 2.7432 2.2225)
			(size 0.3556 1.5494)
			(layers "B.Cu" "B.Mask" "B.Paste")
			(net "GND")
		)
		(pad "9" smd rect
			(at -2.7432 2.2225)
			(size 0.3556 1.5494)
			(layers "B.Cu" "B.Mask" "B.Paste")
			(net "SPI_PEX0_SDIO0_MUX")
		)
		(pad "10" smd rect
			(at -2.7432 1.5875)
			(size 0.3556 1.5494)
			(layers "B.Cu" "B.Mask" "B.Paste")
			(net "SPI_BIC1_MOSI_LS01_R1")
		)
		(pad "11" smd rect
			(at -2.7432 0.9525)
			(size 0.3556 1.5494)
			(layers "B.Cu" "B.Mask" "B.Paste")
			(net "SPI_PEX0_SDIO0_R")
		)
		(pad "12" smd rect
			(at -2.7432 0.3175)
			(size 0.3556 1.5494)
			(layers "B.Cu" "B.Mask" "B.Paste")
			(net "SPI_PEX0_SDIO1_MUX")
		)
		(pad "13" smd rect
			(at -2.7432 -0.3175)
			(size 0.3556 1.5494)
			(layers "B.Cu" "B.Mask" "B.Paste")
			(net "SPI_BIC1_MISO_LS01_R1")
		)
		(pad "14" smd rect
			(at -2.7432 -0.9525)
			(size 0.3556 1.5494)
			(layers "B.Cu" "B.Mask" "B.Paste")
			(net "SPI_PEX0_SDIO1_R")
		)
		(pad "15" smd rect
			(at -2.7432 -1.5875)
			(size 0.3556 1.5494)
			(layers "B.Cu" "B.Mask" "B.Paste")
			(net "SPI_MUX_PEX0_EN_N")
		)
		(pad "16" smd rect
			(at -2.7432 -2.2225)
			(size 0.3556 1.5494)
			(layers "B.Cu" "B.Mask" "B.Paste")
			(net "P3V3_AUX")
		)
	)
	(footprint ""
		(layer "B.Cu")
		(at 292.32479 -293.99992 -90)
		(property "Reference" "C1650"
			(at 0 0 90)
			(layer "B.SilkS")
			(hide yes)
			(effects
				(font
					(size 1.27 1.27)
				)
				(justify mirror)
			)
		)
		(property "Value" ""
			(at 0 0 90)
			(layer "B.Fab")
			(effects
				(font
					(size 1.27 1.27)
				)
				(justify mirror)
			)
		)
		(duplicate_pad_numbers_are_jumpers no)
		(fp_line
			(start -0.299974 0.150114)
			(end 0.299974 0.150114)
			(stroke
				(width 0.1)
				(type default)
			)
			(layer "B.Fab")
		)
		(fp_line
			(start 0.299974 0.150114)
			(end 0.299974 -0.150114)
			(stroke
				(width 0.1)
				(type default)
			)
			(layer "B.Fab")
		)
		(fp_line
			(start -0.299974 -0.150114)
			(end -0.299974 0.150114)
			(stroke
				(width 0.1)
				(type default)
			)
			(layer "B.Fab")
		)
		(fp_line
			(start 0.299974 -0.150114)
			(end -0.299974 -0.150114)
			(stroke
				(width 0.1)
				(type default)
			)
			(layer "B.Fab")
		)
		(pad "1" smd rect
			(at 0.2667 0 90)
			(size 0.3048 0.381)
			(layers "B.Cu" "B.Mask" "B.Paste")
			(net "P0V8_PEX2")
		)
		(pad "2" smd rect
			(at -0.2667 0 90)
			(size 0.3048 0.381)
			(layers "B.Cu" "B.Mask" "B.Paste")
			(net "GND")
		)
	)
	(footprint ""
		(layer "B.Cu")
		(at 401.299934 -301.599854 -90)
		(property "Reference" "C1945"
			(at 0 0 90)
			(layer "B.SilkS")
			(hide yes)
			(effects
				(font
					(size 1.27 1.27)
				)
				(justify mirror)
			)
		)
		(property "Value" ""
			(at 0 0 90)
			(layer "B.Fab")
			(effects
				(font
					(size 1.27 1.27)
				)
				(justify mirror)
			)
		)
		(duplicate_pad_numbers_are_jumpers no)
		(fp_line
			(start -0.299974 0.150114)
			(end 0.299974 0.150114)
			(stroke
				(width 0.1)
				(type default)
			)
			(layer "B.Fab")
		)
		(fp_line
			(start 0.299974 0.150114)
			(end 0.299974 -0.150114)
			(stroke
				(width 0.1)
				(type default)
			)
			(layer "B.Fab")
		)
		(fp_line
			(start -0.299974 -0.150114)
			(end -0.299974 0.150114)
			(stroke
				(width 0.1)
				(type default)
			)
			(layer "B.Fab")
		)
		(fp_line
			(start 0.299974 -0.150114)
			(end -0.299974 -0.150114)
			(stroke
				(width 0.1)
				(type default)
			)
			(layer "B.Fab")
		)
		(pad "1" smd rect
			(at 0.2667 0 90)
			(size 0.3048 0.381)
			(layers "B.Cu" "B.Mask" "B.Paste")
			(net "P0V8_SERDES_VDDA_PEX3")
		)
		(pad "2" smd rect
			(at -0.2667 0 90)
			(size 0.3048 0.381)
			(layers "B.Cu" "B.Mask" "B.Paste")
			(net "GND")
		)
	)
	(footprint ""
		(layer "B.Cu")
		(at 174.800006 -301.599854 -90)
		(property "Reference" "C1430"
			(at 0 0 90)
			(layer "B.SilkS")
			(hide yes)
			(effects
				(font
					(size 1.27 1.27)
				)
				(justify mirror)
			)
		)
		(property "Value" ""
			(at 0 0 90)
			(layer "B.Fab")
			(effects
				(font
					(size 1.27 1.27)
				)
				(justify mirror)
			)
		)
		(duplicate_pad_numbers_are_jumpers no)
		(fp_line
			(start -0.299974 0.150114)
			(end 0.299974 0.150114)
			(stroke
				(width 0.1)
				(type default)
			)
			(layer "B.Fab")
		)
		(fp_line
			(start 0.299974 0.150114)
			(end 0.299974 -0.150114)
			(stroke
				(width 0.1)
				(type default)
			)
			(layer "B.Fab")
		)
		(fp_line
			(start -0.299974 -0.150114)
			(end -0.299974 0.150114)
			(stroke
				(width 0.1)
				(type default)
			)
			(layer "B.Fab")
		)
		(fp_line
			(start 0.299974 -0.150114)
			(end -0.299974 -0.150114)
			(stroke
				(width 0.1)
				(type default)
			)
			(layer "B.Fab")
		)
		(pad "1" smd rect
			(at 0.2667 0 90)
			(size 0.3048 0.381)
			(layers "B.Cu" "B.Mask" "B.Paste")
			(net "P0V8_SERDES_VDDA_PEX1")
		)
		(pad "2" smd rect
			(at -0.2667 0 90)
			(size 0.3048 0.381)
			(layers "B.Cu" "B.Mask" "B.Paste")
			(net "GND")
		)
	)
)
